# S9S_MB_2U (Grand Teton) — schematic netlist excerpt (pin names and nets, part order shuffled) for the footprints in the layout excerpt that follows; sources: Cadence DE-HDL packaged netlist, KiCad conversion of 03242023_DA0F0TMBIJ0_F0T_Motherboard_J_brd_V01_OCP.brd

J4  SCONN288_ADR50017P087CC  SCONN288_ADR50017-P087CC IO  pkg DDR288S_1-1VXB  page 85
  VIN_BULK0  = P12V_S3_AUX_CPU0_NVDIMM
  RFU0  = TP_CHB_CPU0_DIMM2_FRU_0
  VIN_MGMT  = P3V3_AUX
  HSCL  = I3C_SPD_DDRABCD_CPU0_LVC1_SCL_3
  HSDA  = I3C_SPD_DDRABCD_CPU0_LVC1_SDA
  VSS0  = GND
  DQ0_A  = M_B_CPU0_SA_DQ<0>
  VSS1  = GND
  DQ1_A  = M_B_CPU0_SA_DQ<1>
  VSS2  = GND
  DQS0_A_T  = M_B_CPU0_SA_DQS_DP<0>
  DQS0_A_C  = M_B_CPU0_SA_DQS_DN<0>
  VSS3  = GND
  DQ4_A  = M_B_CPU0_SA_DQ<4>
  VSS4  = GND
  DQ5_A  = M_B_CPU0_SA_DQ<5>
  VSS5  = GND
  DQ8_A  = M_B_CPU0_SA_DQ<8>
  VSS6  = GND
  DQ9_A  = M_B_CPU0_SA_DQ<9>
  VSS7  = GND
  DQS1_A_T  = M_B_CPU0_SA_DQS_DP<1>
  DQS1_A_C  = M_B_CPU0_SA_DQS_DN<1>
  VSS8  = GND
  DQ12_A  = M_B_CPU0_SA_DQ<12>
  VSS9  = GND
  DQ13_A  = M_B_CPU0_SA_DQ<13>
  VSS10  = GND
  DQ16_A  = M_B_CPU0_SA_DQ<16>
  VSS11  = GND
  DQ17_A  = M_B_CPU0_SA_DQ<17>
  VSS12  = GND
  DQS2_A_T  = M_B_CPU0_SA_DQS_DP<2>
  DQS2_A_C  = M_B_CPU0_SA_DQS_DN<2>
  VSS13  = GND
  DQ20_A  = M_B_CPU0_SA_DQ<20>
  VSS14  = GND
  DQ21_A  = M_B_CPU0_SA_DQ<21>
  VSS15  = GND
  DQ24_A  = M_B_CPU0_SA_DQ<24>
  VSS16  = GND
  DQ25_A  = M_B_CPU0_SA_DQ<25>
  VSS17  = GND
  DQS3_A_T  = M_B_CPU0_SA_DQS_DP<3>
  DQS3_A_C  = M_B_CPU0_SA_DQS_DN<3>
  VSS18  = GND
  DQ28_A  = M_B_CPU0_SA_DQ<28>
  VSS19  = GND
  DQ29_A  = M_B_CPU0_SA_DQ<29>
  VSS20  = GND
  CB0_A  = M_B_CPU0_SA_CB<0>
  VSS21  = GND
  CB1_A  = M_B_CPU0_SA_CB<1>
  VSS22  = GND
  DQS4_A_T  = M_B_CPU0_SA_DQS_DP<4>
  DQS4_A_C  = M_B_CPU0_SA_DQS_DN<4>
  VSS23  = GND
  CB4_A  = M_B_CPU0_SA_CB<4>
  VSS24  = GND
  CB5_A  = M_B_CPU0_SA_CB<5>
  VSS25  = GND
  ALERT_N  = M_B_CPU0_ALERT_N
  VSS26  = GND
  CS0_A_N  = M_B_CPU0_SA_CS_N<2>
  VSS27  = GND
  CA0_A  = M_B_CPU0_SA_CA<0>
  VSS28  = GND
  CA2_A  = M_B_CPU0_SA_CA<2>
  VSS29  = GND
  CA4_A  = M_B_CPU0_SA_CA<4>
  VSS30  = GND
  CA6_A  = M_B_CPU0_SA_CA<6>
  VSS31  = GND
  PAR_A  = M_B_CPU0_SA_PAR
  VSS32  = GND
  CA0_B  = M_B_CPU0_SB_CA<0>
  VSS33  = GND
  CA2_B  = M_B_CPU0_SB_CA<2>
  VSS34  = GND
  CA4_B  = M_B_CPU0_SB_CA<4>
  VSS35  = GND
  CA6_B  = M_B_CPU0_SB_CA<6>
  VSS36  = GND
  CS0_B_N  = M_B_CPU0_SB_CS_N<2>
  VSS37  = GND
  \lbd||rsp_a_n\  = M_B_CPU0_SA_RSP<1>
  \lbs||rsp_b_n\  = M_B_CPU0_SB_RSP<1>
  VSS38  = GND
  CB4_B  = M_B_CPU0_SB_CB<4>
  VSS39  = GND
  CB5_B  = M_B_CPU0_SB_CB<5>
  VSS40  = GND
  \dqs9_b_t||tdqs9_b_t||dbi4_b_n\  = M_B_CPU0_SB_DQS_DP<9>
  \dqs9_b_c||tdqs9_b_c\  = M_B_CPU0_SB_DQS_DN<9>
  VSS41  = GND
  CB0_B  = M_B_CPU0_SB_CB<0>
  VSS42  = GND
  CB1_B  = M_B_CPU0_SB_CB<1>
  VSS43  = GND
  DQ0_B  = M_B_CPU0_SB_DQ<0>
  VSS44  = GND
  DQ1_B  = M_B_CPU0_SB_DQ<1>
  VSS45  = GND
  DQS0_B_T  = M_B_CPU0_SB_DQS_DP<0>
  DQS0_B_C  = M_B_CPU0_SB_DQS_DN<0>
  VSS46  = GND
  DQ4_B  = M_B_CPU0_SB_DQ<4>
  VSS47  = GND
  DQ5_B  = M_B_CPU0_SB_DQ<5>
  VSS48  = GND
  DQ8_B  = M_B_CPU0_SB_DQ<8>
  VSS49  = GND
  DQ9_B  = M_B_CPU0_SB_DQ<9>
  VSS50  = GND
  DQS1_B_T  = M_B_CPU0_SB_DQS_DP<1>
  DQS1_B_C  = M_B_CPU0_SB_DQS_DN<1>
  VSS51  = GND
  DQ12_B  = M_B_CPU0_SB_DQ<12>
  VSS52  = GND
  DQ13_B  = M_B_CPU0_SB_DQ<13>
  VSS53  = GND
  DQ16_B  = M_B_CPU0_SB_DQ<16>
  VSS54  = GND
  DQ17_B  = M_B_CPU0_SB_DQ<17>
  VSS55  = GND
  DQS2_B_T  = M_B_CPU0_SB_DQS_DP<2>
  DQS2_B_C  = M_B_CPU0_SB_DQS_DN<2>
  VSS56  = GND
  DQ20_B  = M_B_CPU0_SB_DQ<20>
  VSS57  = GND
  DQ21_B  = M_B_CPU0_SB_DQ<21>
  VSS58  = GND
  DQ24_B  = M_B_CPU0_SB_DQ<24>
  VSS59  = GND
  DQ25_B  = M_B_CPU0_SB_DQ<25>
  VSS60  = GND
  DQS3_B_T  = M_B_CPU0_SB_DQS_DP<3>
  DQS3_B_C  = M_B_CPU0_SB_DQS_DN<3>
  VSS61  = GND
  DQ28_B  = M_B_CPU0_SB_DQ<28>
  VSS62  = GND
  DQ29_B  = M_B_CPU0_SB_DQ<29>
  VSS63  = GND
  RFU1  = TP_CHB_CPU0_DIMM2_FRU_1
  VIN_BULK1  = P12V_S3_AUX_CPU0_NVDIMM
  VIN_BULK2  = P12V_S3_AUX_CPU0_NVDIMM
  \pwr_good||fail_n\  = PWRGD_CHB_CPU0_DIMM2
  HSA  = PD_CHB_CPU0_DIMM2_SAA
  RFU2  = TP_CHB_CPU0_DIMM2_FRU_2
  RFU3  = TP_CHB_CPU0_DIMM2_FRU_3
  VSS64  = GND
  DQ2_A  = M_B_CPU0_SA_DQ<2>
  VSS65  = GND
  DQ3_A  = M_B_CPU0_SA_DQ<3>
  VSS66  = GND
  \dqs5_a_c||tdqs5_a_c||dqs5_a_t||tdqs5_a_t\  = M_B_CPU0_SA_DQS_DN<5>
  \dqs5_a_t||tdqs5_a_t\  = M_B_CPU0_SA_DQS_DP<5>
  VSS67  = GND
  DQ6_A  = M_B_CPU0_SA_DQ<6>
  VSS68  = GND
  DQ7_A  = M_B_CPU0_SA_DQ<7>
  VSS69  = GND
  DQ10_A  = M_B_CPU0_SA_DQ<10>
  VSS70  = GND
  DQ11_A  = M_B_CPU0_SA_DQ<11>
  VSS71  = GND
  \dqs6_a_c||tdqs6_a_c||dqs6_a_t||tdqs6_a_t\  = M_B_CPU0_SA_DQS_DN<6>
  \dqs6_a_t||tdqs6_a_t\  = M_B_CPU0_SA_DQS_DP<6>
  VSS72  = GND
  DQ14_A  = M_B_CPU0_SA_DQ<14>
  VSS73  = GND
  DQ15_A  = M_B_CPU0_SA_DQ<15>
  VSS74  = GND
  DQ18_A  = M_B_CPU0_SA_DQ<18>
  VSS75  = GND
  DQ19_A  = M_B_CPU0_SA_DQ<19>
  VSS76  = GND
  \dqs7_a_c||tdqs7_a_c\  = M_B_CPU0_SA_DQS_DN<7>
  \dqs7_a_t||tdqs7_a_t\  = M_B_CPU0_SA_DQS_DP<7>
  VSS77  = GND
  DQ22_A  = M_B_CPU0_SA_DQ<22>
  VSS78  = GND
  DQ23_A  = M_B_CPU0_SA_DQ<23>
  VSS79  = GND
  DQ26_A  = M_B_CPU0_SA_DQ<26>
  VSS80  = GND
  DQ27_A  = M_B_CPU0_SA_DQ<27>
  VSS81  = GND
  \dqs8_a_c||tdqs8_a_c\  = M_B_CPU0_SA_DQS_DN<8>
  \dqs8_a_t||tdqs8_a_t\  = M_B_CPU0_SA_DQS_DP<8>
  VSS82  = GND
  DQ30_A  = M_B_CPU0_SA_DQ<30>
  VSS83  = GND
  DQ31_A  = M_B_CPU0_SA_DQ<31>
  VSS84  = GND
  CB2_A  = M_B_CPU0_SA_CB<2>
  VSS85  = GND
  CB3_A  = M_B_CPU0_SA_CB<3>
  VSS86  = GND
  \dqs9_a_c||tdqs9_a_c\  = M_B_CPU0_SA_DQS_DN<9>
  \dqs9_a_t||tdqs9_a_t\  = M_B_CPU0_SA_DQS_DP<9>
  VSS87  = GND
  CB6_A  = M_B_CPU0_SA_CB<6>
  VSS88  = GND
  CB7_A  = M_B_CPU0_SA_CB<7>
  VSS89  = GND
  RESET_N  = RST_M_AB_CPU0_FPGA_N
  VSS90  = GND
  CS1_A_N  = M_B_CPU0_SA_CS_N<3>
  VSS91  = GND
  CA1_A  = M_B_CPU0_SA_CA<1>
  VSS92  = GND
  CA3_A  = M_B_CPU0_SA_CA<3>
  VSS93  = GND
  CA5_A  = M_B_CPU0_SA_CA<5>
  VSS94  = GND
  CK_T  = M_B_CPU0_CLK_DP<1>
  CK_C  = M_B_CPU0_CLK_DN<1>
  VSS95  = GND
  RFU4  = TP_CHB_CPU0_DIMM2_FRU_4
  CA1_B  = M_B_CPU0_SB_CA<1>
  VSS96  = GND
  CA3_B  = M_B_CPU0_SB_CA<3>
  VSS97  = GND
  CA5_B  = M_B_CPU0_SB_CA<5>
  VSS98  = GND
  PAR_B  = M_B_CPU0_SB_PAR
  VSS99  = GND
  CS1_B_N  = M_B_CPU0_SB_CS_N<3>
  VSS100  = GND
  RFU5  = TP_CHB_CPU0_DIMM2_FRU_5
  RFU6  = TP_CHB_CPU0_DIMM2_FRU_6
  VSS101  = GND
  CB6_B  = M_B_CPU0_SB_CB<6>
  VSS102  = GND
  CB7_B  = M_B_CPU0_SB_CB<7>
  VSS103  = GND
  DQS4_B_C  = M_B_CPU0_SB_DQS_DN<4>
  DQS4_B_T  = M_B_CPU0_SB_DQS_DP<4>
  VSS104  = GND
  CB2_B  = M_B_CPU0_SB_CB<2>
  VSS105  = GND
  CB3_B  = M_B_CPU0_SB_CB<3>
  VSS106  = GND
  DQ2_B  = M_B_CPU0_SB_DQ<2>
  VSS107  = GND
  DQ3_B  = M_B_CPU0_SB_DQ<3>
  VSS108  = GND
  \dqs5_b_c||tdqs5_b_c\  = M_B_CPU0_SB_DQS_DN<5>
  \dqs5_b_t||tdqs5_b_t\  = M_B_CPU0_SB_DQS_DP<5>
  VSS109  = GND
  DQ6_B  = M_B_CPU0_SB_DQ<6>
  VSS110  = GND
  DQ7_B  = M_B_CPU0_SB_DQ<7>
  VSS111  = GND
  DQ10_B  = M_B_CPU0_SB_DQ<10>
  VSS112  = GND
  DQ11_B  = M_B_CPU0_SB_DQ<11>
  VSS113  = GND
  \dqs6_b_c||tdqs6_b_c\  = M_B_CPU0_SB_DQS_DN<6>
  \dqs6_b_t||tdqs6_b_t\  = M_B_CPU0_SB_DQS_DP<6>
  VSS114  = GND
  DQ14_B  = M_B_CPU0_SB_DQ<14>
  VSS115  = GND
  DQ15_B  = M_B_CPU0_SB_DQ<15>
  VSS116  = GND
  DQ18_B  = M_B_CPU0_SB_DQ<18>
  VSS117  = GND
  DQ19_B  = M_B_CPU0_SB_DQ<19>
  VSS118  = GND
  \dqs7_b_c||tdqs7_b_c\  = M_B_CPU0_SB_DQS_DN<7>
  \dqs7_b_t||tdqs7_b_t\  = M_B_CPU0_SB_DQS_DP<7>
  VSS119  = GND
  DQ22_B  = M_B_CPU0_SB_DQ<22>
  VSS120  = GND
  DQ23_B  = M_B_CPU0_SB_DQ<23>
  VSS121  = GND
  DQ26_B  = M_B_CPU0_SB_DQ<26>
  VSS122  = GND
  DQ27_B  = M_B_CPU0_SB_DQ<27>
  VSS123  = GND
  \dqs8_b_c||tdqs8_b_c\  = M_B_CPU0_SB_DQS_DN<8>
  \dqs8_b_t||tdqs8_b_t\  = M_B_CPU0_SB_DQS_DP<8>
  VSS124  = GND
  DQ30_B  = M_B_CPU0_SB_DQ<30>
  VSS125  = GND
  DQ31_B  = M_B_CPU0_SB_DQ<31>
  VSS126  = GND
  G1  = GND
  G2  = GND
  G3  = GND

(kicad_pcb
	(version 20260206)
	(generator "pcbnew")
	(generator_version "10.0")
	(general
		(thickness 1.6)
		(legacy_teardrops no)
	)
	(paper "A4")
	(title_block
		(title "03242023_DA0F0TMBIJ0_F0T_Motherboard_J_brd_V01_OCP.brd")
		(comment 1 "Grand Teton / footprint 1229 of 6105 (J4), pads 138-182 of 291")
	)
	(layers
		(0 "F.Cu" signal "TOP")
		(4 "In1.Cu" signal "GND")
		(6 "In2.Cu" signal "IN1")
		(8 "In3.Cu" signal "GND1")
		(10 "In4.Cu" signal "IN2")
		(12 "In5.Cu" signal "GND2")
		(14 "In6.Cu" signal "IN3")
		(16 "In7.Cu" signal "GND3")
		(18 "In8.Cu" signal "VCC")
		(20 "In9.Cu" signal "VCC1")
		(22 "In10.Cu" signal "GND4")
		(24 "In11.Cu" signal "IN4")
		(26 "In12.Cu" signal "GND5")
		(28 "In13.Cu" signal "IN5")
		(30 "In14.Cu" signal "GND6")
		(32 "In15.Cu" signal "IN6")
		(34 "In16.Cu" signal "GND7")
		(2 "B.Cu" signal "BOTTOM")
		(9 "F.Adhes" user "F.Adhesive")
		(11 "B.Adhes" user "B.Adhesive")
		(13 "F.Paste" user "Package Geometry/Pastemask Top")
		(15 "B.Paste" user "Package Geometry/Pastemask Bottom")
		(5 "F.SilkS" user "Ref Des/Silkscreen Top")
		(7 "B.SilkS" user "Ref Des/Silkscreen Bottom")
		(1 "F.Mask" user "Board Geometry/Soldermask Top")
		(3 "B.Mask" user "Board Geometry/Soldermask Bottom")
		(17 "Dwgs.User" user "User.Drawings")
		(19 "Cmts.User" user "User.Comments")
		(21 "Eco1.User" user "User.Eco1")
		(23 "Eco2.User" user "User.Eco2")
		(25 "Edge.Cuts" user "Board Geometry/Outline")
		(27 "Margin" user)
		(31 "F.CrtYd" user "Package Geometry/Place Bound Top")
		(29 "B.CrtYd" user "Package Geometry/Place Bound Bottom")
		(35 "F.Fab" user "Ref Des/Assembly Top")
		(33 "B.Fab" user "Ref Des/Assembly Bottom")
	)
	(footprint ""
		(layer "F.Cu")
		(at 295.849548 -258.091686)
		(property "Reference" "J4"
			(at -3.683 -81.702148 0)
			(unlocked yes)
			(layer "F.SilkS")
			(effects
				(font
					(size 0.7874 0.5842)
					(thickness 0.1524)
				)
				(justify left)
			)
		)
		(property "Value" ""
			(at 0 0 0)
			(layer "F.Fab")
			(effects
				(font
					(size 1.27 1.27)
				)
			)
		)
		(duplicate_pad_numbers_are_jumpers no)
		(pad "138" smd rect
			(at -2.050034 58.224928 270)
			(size 0.519938 1.4986)
			(layers "F.Cu" "F.Mask" "F.Paste")
			(net "M_B_CPU0_SB_DQS_DN<3>")
		)
		(pad "139" smd rect
			(at -2.050034 59.075066 270)
			(size 0.519938 1.4986)
			(layers "F.Cu" "F.Mask" "F.Paste")
			(net "GND")
		)
		(pad "140" smd rect
			(at -2.050034 59.92495 270)
			(size 0.519938 1.4986)
			(layers "F.Cu" "F.Mask" "F.Paste")
			(net "M_B_CPU0_SB_DQ<28>")
		)
		(pad "141" smd rect
			(at -2.050034 60.775088 270)
			(size 0.519938 1.4986)
			(layers "F.Cu" "F.Mask" "F.Paste")
			(net "GND")
		)
		(pad "142" smd rect
			(at -2.050034 61.624972 270)
			(size 0.519938 1.4986)
			(layers "F.Cu" "F.Mask" "F.Paste")
			(net "M_B_CPU0_SB_DQ<29>")
		)
		(pad "143" smd rect
			(at -2.050034 62.47511 270)
			(size 0.519938 1.4986)
			(layers "F.Cu" "F.Mask" "F.Paste")
			(net "GND")
		)
		(pad "144" smd rect
			(at -2.050034 63.324994 270)
			(size 0.519938 1.4986)
			(layers "F.Cu" "F.Mask" "F.Paste")
			(net "TP_CHB_CPU0_DIMM2_FRU_1")
		)
		(pad "145" smd rect
			(at 2.050034 -63.324994 270)
			(size 0.519938 1.4986)
			(layers "F.Cu" "F.Mask" "F.Paste")
			(net "P12V_S3_AUX_CPU0_NVDIMM")
		)
		(pad "146" smd rect
			(at 2.050034 -62.47511 270)
			(size 0.519938 1.4986)
			(layers "F.Cu" "F.Mask" "F.Paste")
			(net "P12V_S3_AUX_CPU0_NVDIMM")
		)
		(pad "147" smd rect
			(at 2.050034 -61.624972 270)
			(size 0.519938 1.4986)
			(layers "F.Cu" "F.Mask" "F.Paste")
			(net "PWRGD_CHB_CPU0_DIMM2")
		)
		(pad "148" smd rect
			(at 2.050034 -60.775088 270)
			(size 0.519938 1.4986)
			(layers "F.Cu" "F.Mask" "F.Paste")
			(net "PD_CHB_CPU0_DIMM2_SAA")
		)
		(pad "149" smd rect
			(at 2.050034 -59.92495 270)
			(size 0.519938 1.4986)
			(layers "F.Cu" "F.Mask" "F.Paste")
			(net "TP_CHB_CPU0_DIMM2_FRU_2")
		)
		(pad "150" smd rect
			(at 2.050034 -59.075066 270)
			(size 0.519938 1.4986)
			(layers "F.Cu" "F.Mask" "F.Paste")
			(net "TP_CHB_CPU0_DIMM2_FRU_3")
		)
		(pad "151" smd rect
			(at 2.050034 -58.224928 270)
			(size 0.519938 1.4986)
			(layers "F.Cu" "F.Mask" "F.Paste")
			(net "GND")
		)
		(pad "152" smd rect
			(at 2.050034 -57.375044 270)
			(size 0.519938 1.4986)
			(layers "F.Cu" "F.Mask" "F.Paste")
			(net "M_B_CPU0_SA_DQ<2>")
		)
		(pad "153" smd rect
			(at 2.050034 -56.524906 270)
			(size 0.519938 1.4986)
			(layers "F.Cu" "F.Mask" "F.Paste")
			(net "GND")
		)
		(pad "154" smd rect
			(at 2.050034 -55.675022 270)
			(size 0.519938 1.4986)
			(layers "F.Cu" "F.Mask" "F.Paste")
			(net "M_B_CPU0_SA_DQ<3>")
		)
		(pad "155" smd rect
			(at 2.050034 -54.824884 270)
			(size 0.519938 1.4986)
			(layers "F.Cu" "F.Mask" "F.Paste")
			(net "GND")
		)
		(pad "156" smd rect
			(at 2.050034 -53.975 270)
			(size 0.519938 1.4986)
			(layers "F.Cu" "F.Mask" "F.Paste")
			(net "M_B_CPU0_SA_DQS_DN<5>")
		)
		(pad "157" smd rect
			(at 2.050034 -53.125116 270)
			(size 0.519938 1.4986)
			(layers "F.Cu" "F.Mask" "F.Paste")
			(net "M_B_CPU0_SA_DQS_DP<5>")
		)
		(pad "158" smd rect
			(at 2.050034 -52.274978 270)
			(size 0.519938 1.4986)
			(layers "F.Cu" "F.Mask" "F.Paste")
			(net "GND")
		)
		(pad "159" smd rect
			(at 2.050034 -51.425094 270)
			(size 0.519938 1.4986)
			(layers "F.Cu" "F.Mask" "F.Paste")
			(net "M_B_CPU0_SA_DQ<6>")
		)
		(pad "160" smd rect
			(at 2.050034 -50.574956 270)
			(size 0.519938 1.4986)
			(layers "F.Cu" "F.Mask" "F.Paste")
			(net "GND")
		)
		(pad "161" smd rect
			(at 2.050034 -49.725072 270)
			(size 0.519938 1.4986)
			(layers "F.Cu" "F.Mask" "F.Paste")
			(net "M_B_CPU0_SA_DQ<7>")
		)
		(pad "162" smd rect
			(at 2.050034 -48.874934 270)
			(size 0.519938 1.4986)
			(layers "F.Cu" "F.Mask" "F.Paste")
			(net "GND")
		)
		(pad "163" smd rect
			(at 2.050034 -48.02505 270)
			(size 0.519938 1.4986)
			(layers "F.Cu" "F.Mask" "F.Paste")
			(net "M_B_CPU0_SA_DQ<10>")
		)
		(pad "164" smd rect
			(at 2.050034 -47.174912 270)
			(size 0.519938 1.4986)
			(layers "F.Cu" "F.Mask" "F.Paste")
			(net "GND")
		)
		(pad "165" smd rect
			(at 2.050034 -46.325028 270)
			(size 0.519938 1.4986)
			(layers "F.Cu" "F.Mask" "F.Paste")
			(net "M_B_CPU0_SA_DQ<11>")
		)
		(pad "166" smd rect
			(at 2.050034 -45.47489 270)
			(size 0.519938 1.4986)
			(layers "F.Cu" "F.Mask" "F.Paste")
			(net "GND")
		)
		(pad "167" smd rect
			(at 2.050034 -44.625006 270)
			(size 0.519938 1.4986)
			(layers "F.Cu" "F.Mask" "F.Paste")
			(net "M_B_CPU0_SA_DQS_DN<6>")
		)
		(pad "168" smd rect
			(at 2.050034 -43.775122 270)
			(size 0.519938 1.4986)
			(layers "F.Cu" "F.Mask" "F.Paste")
			(net "M_B_CPU0_SA_DQS_DP<6>")
		)
		(pad "169" smd rect
			(at 2.050034 -42.924984 270)
			(size 0.519938 1.4986)
			(layers "F.Cu" "F.Mask" "F.Paste")
			(net "GND")
		)
		(pad "170" smd rect
			(at 2.050034 -42.0751 270)
			(size 0.519938 1.4986)
			(layers "F.Cu" "F.Mask" "F.Paste")
			(net "M_B_CPU0_SA_DQ<14>")
		)
		(pad "171" smd rect
			(at 2.050034 -41.224962 270)
			(size 0.519938 1.4986)
			(layers "F.Cu" "F.Mask" "F.Paste")
			(net "GND")
		)
		(pad "172" smd rect
			(at 2.050034 -40.375078 270)
			(size 0.519938 1.4986)
			(layers "F.Cu" "F.Mask" "F.Paste")
			(net "M_B_CPU0_SA_DQ<15>")
		)
		(pad "173" smd rect
			(at 2.050034 -39.52494 270)
			(size 0.519938 1.4986)
			(layers "F.Cu" "F.Mask" "F.Paste")
			(net "GND")
		)
		(pad "174" smd rect
			(at 2.050034 -38.675056 270)
			(size 0.519938 1.4986)
			(layers "F.Cu" "F.Mask" "F.Paste")
			(net "M_B_CPU0_SA_DQ<18>")
		)
		(pad "175" smd rect
			(at 2.050034 -37.824918 270)
			(size 0.519938 1.4986)
			(layers "F.Cu" "F.Mask" "F.Paste")
			(net "GND")
		)
		(pad "176" smd rect
			(at 2.050034 -36.975034 270)
			(size 0.519938 1.4986)
			(layers "F.Cu" "F.Mask" "F.Paste")
			(net "M_B_CPU0_SA_DQ<19>")
		)
		(pad "177" smd rect
			(at 2.050034 -36.124896 270)
			(size 0.519938 1.4986)
			(layers "F.Cu" "F.Mask" "F.Paste")
			(net "GND")
		)
		(pad "178" smd rect
			(at 2.050034 -35.275012 270)
			(size 0.519938 1.4986)
			(layers "F.Cu" "F.Mask" "F.Paste")
			(net "M_B_CPU0_SA_DQS_DN<7>")
		)
		(pad "179" smd rect
			(at 2.050034 -34.425128 270)
			(size 0.519938 1.4986)
			(layers "F.Cu" "F.Mask" "F.Paste")
			(net "M_B_CPU0_SA_DQS_DP<7>")
		)
		(pad "180" smd rect
			(at 2.050034 -33.57499 270)
			(size 0.519938 1.4986)
			(layers "F.Cu" "F.Mask" "F.Paste")
			(net "GND")
		)
		(pad "181" smd rect
			(at 2.050034 -32.725106 270)
			(size 0.519938 1.4986)
			(layers "F.Cu" "F.Mask" "F.Paste")
			(net "M_B_CPU0_SA_DQ<22>")
		)
		(pad "182" smd rect
			(at 2.050034 -31.874968 270)
			(size 0.519938 1.4986)
			(layers "F.Cu" "F.Mask" "F.Paste")
			(net "GND")
		)
	)
)
